(kicad_pcb
	(version 20260206)
	(generator "pcbnew")
	(generator_version "10.0")
	(general
		(thickness 1.6)
		(legacy_teardrops no)
	)
	(paper "A4")
	(title_block
		(title "peb — Lightning_PEB_BRD.brd")
		(comment 1 "Lightning (Wiwynn / Facebook NVMe JBOF) / footprint 1445 of 2563 (U1), pads 1-117 of 1311")
	)
	(layers
		(0 "F.Cu" signal "TOP")
		(4 "In1.Cu" signal "L2GND")
		(6 "In2.Cu" signal "L3")
		(8 "In3.Cu" signal "L4VCC")
		(10 "In4.Cu" signal "L5VCC")
		(12 "In5.Cu" signal "L6")
		(14 "In6.Cu" signal "L7GND")
		(2 "B.Cu" signal "BOTTOM")
		(9 "F.Adhes" user "F.Adhesive")
		(11 "B.Adhes" user "B.Adhesive")
		(13 "F.Paste" user "Package Geometry/Pastemask Top")
		(15 "B.Paste" user "Package Geometry/Pastemask Bottom")
		(5 "F.SilkS" user "Ref Des/Silkscreen Top")
		(7 "B.SilkS" user "Ref Des/Silkscreen Bottom")
		(1 "F.Mask" user "Board Geometry/Soldermask Top")
		(3 "B.Mask" user "Board Geometry/Soldermask Bottom")
		(17 "Dwgs.User" user "User.Drawings")
		(19 "Cmts.User" user "User.Comments")
		(21 "Eco1.User" user "User.Eco1")
		(23 "Eco2.User" user "User.Eco2")
		(25 "Edge.Cuts" user "Board Geometry/Outline")
		(27 "Margin" user)
		(31 "F.CrtYd" user "Package Geometry/Place Bound Top")
		(29 "B.CrtYd" user "Package Geometry/Place Bound Bottom")
		(35 "F.Fab" user "Ref Des/Assembly Top")
		(33 "B.Fab" user "Ref Des/Assembly Bottom")
	)
	(footprint ""
		(layer "F.Cu")
		(at 240.599976 -47.999904 -90)
		(property "Reference" "U1"
			(at 0 0 270)
			(layer "F.SilkS")
			(hide yes)
			(effects
				(font
					(size 1.27 1.27)
				)
			)
		)
		(property "Value" "PM8546A-FEIP-GP"
			(at -25.785064 -6.40334 270)
			(unlocked yes)
			(layer "F.Fab")
			(hide yes)
			(effects
				(font
					(size 1.016 1.016)
					(thickness 0.1524)
				)
			)
		)
		(property "Device Type" "BGA1311C37D5H134"
			(at -25.785064 -7.92734 270)
			(unlocked yes)
			(layer "F.Fab")
			(hide yes)
			(effects
				(font
					(size 1.016 1.016)
					(thickness 0.1524)
				)
			)
		)
		(duplicate_pad_numbers_are_jumpers no)
		(pad "A2" smd circle
			(at -16.999966 -17.999964 270)
			(size 0.508 0.508)
			(layers "F.Cu" "F.Mask" "F.Paste")
			(net "GND")
		)
		(pad "A3" smd circle
			(at -15.999968 -17.999964 270)
			(size 0.508 0.508)
			(layers "F.Cu" "F.Mask" "F.Paste")
			(net "GND")
		)
		(pad "A4" smd circle
			(at -14.99997 -17.999964 270)
			(size 0.4572 0.4572)
			(layers "F.Cu" "F.Mask" "F.Paste")
			(net "GND")
		)
		(pad "A5" smd circle
			(at -13.999972 -17.999964 270)
			(size 0.4572 0.4572)
			(layers "F.Cu" "F.Mask" "F.Paste")
			(net "GND")
		)
		(pad "A6" smd circle
			(at -12.999974 -17.999964 270)
			(size 0.4572 0.4572)
			(layers "F.Cu" "F.Mask" "F.Paste")
			(net "GND")
		)
		(pad "A7" smd circle
			(at -11.999976 -17.999964 270)
			(size 0.4572 0.4572)
			(layers "F.Cu" "F.Mask" "F.Paste")
			(net "GND")
		)
		(pad "A9" smd circle
			(at -9.99998 -17.999964 270)
			(size 0.4572 0.4572)
			(layers "F.Cu" "F.Mask" "F.Paste")
			(net "PCIE_TX_CAP_N30")
		)
		(pad "A11" smd circle
			(at -7.999984 -17.999964 270)
			(size 0.4572 0.4572)
			(layers "F.Cu" "F.Mask" "F.Paste")
			(net "PCIE_TX_CAP_N28")
		)
		(pad "A13" smd circle
			(at -5.999988 -17.999964 270)
			(size 0.4572 0.4572)
			(layers "F.Cu" "F.Mask" "F.Paste")
			(net "PCIE_TX_CAP_N26")
		)
		(pad "A15" smd circle
			(at -3.999992 -17.999964 270)
			(size 0.4572 0.4572)
			(layers "F.Cu" "F.Mask" "F.Paste")
			(net "PCIE_TX_CAP_N24")
		)
		(pad "A16" smd circle
			(at -2.999994 -17.999964 270)
			(size 0.4572 0.4572)
			(layers "F.Cu" "F.Mask" "F.Paste")
			(net "GND")
		)
		(pad "A18" smd circle
			(at -0.999998 -17.999964 270)
			(size 0.4572 0.4572)
			(layers "F.Cu" "F.Mask" "F.Paste")
			(net "PCIE_TX_CAP_N22")
		)
		(pad "A20" smd circle
			(at 0.999998 -17.999964 270)
			(size 0.4572 0.4572)
			(layers "F.Cu" "F.Mask" "F.Paste")
			(net "PCIE_TX_CAP_N20")
		)
		(pad "A22" smd circle
			(at 2.999994 -17.999964 270)
			(size 0.4572 0.4572)
			(layers "F.Cu" "F.Mask" "F.Paste")
			(net "PCIE_TX_CAP_N18")
		)
		(pad "A24" smd circle
			(at 4.99999 -17.999964 270)
			(size 0.4572 0.4572)
			(layers "F.Cu" "F.Mask" "F.Paste")
			(net "PCIE_TX_CAP_N16")
		)
		(pad "A25" smd circle
			(at 5.999988 -17.999964 270)
			(size 0.4572 0.4572)
			(layers "F.Cu" "F.Mask" "F.Paste")
			(net "GND")
		)
		(pad "A27" smd circle
			(at 7.999984 -17.999964 270)
			(size 0.4572 0.4572)
			(layers "F.Cu" "F.Mask" "F.Paste")
			(net "PCIE_TX_CAP_N14")
		)
		(pad "A29" smd circle
			(at 9.99998 -17.999964 270)
			(size 0.4572 0.4572)
			(layers "F.Cu" "F.Mask" "F.Paste")
			(net "PCIE_TX_CAP_N12")
		)
		(pad "A31" smd circle
			(at 11.999976 -17.999964 270)
			(size 0.4572 0.4572)
			(layers "F.Cu" "F.Mask" "F.Paste")
			(net "PCIE_TX_CAP_N10")
		)
		(pad "A33" smd circle
			(at 13.999972 -17.999964 270)
			(size 0.4572 0.4572)
			(layers "F.Cu" "F.Mask" "F.Paste")
			(net "PCIE_TX_CAP_N8")
		)
		(pad "A34" smd circle
			(at 14.99997 -17.999964 270)
			(size 0.4572 0.4572)
			(layers "F.Cu" "F.Mask" "F.Paste")
			(net "GND")
		)
		(pad "A35" smd circle
			(at 15.999968 -17.999964 270)
			(size 0.508 0.508)
			(layers "F.Cu" "F.Mask" "F.Paste")
			(net "PCIE_TX_CAP_P7")
		)
		(pad "A36" smd circle
			(at 16.999966 -17.999964 270)
			(size 0.508 0.508)
			(layers "F.Cu" "F.Mask" "F.Paste")
			(net "PCIE_TX_CAP_N7")
		)
		(pad "AA1" smd circle
			(at -17.999964 1.999996 270)
			(size 0.4572 0.4572)
			(layers "F.Cu" "F.Mask" "F.Paste")
			(net "PCIE_TX_CAP_N49")
		)
		(pad "AA2" smd circle
			(at -16.999966 1.999996 270)
			(size 0.4572 0.4572)
			(layers "F.Cu" "F.Mask" "F.Paste")
			(net "PCIE_TX_CAP_P49")
		)
		(pad "AA3" smd circle
			(at -15.999968 1.999996 270)
			(size 0.4572 0.4572)
			(layers "F.Cu" "F.Mask" "F.Paste")
			(net "GND")
		)
		(pad "AA4" smd circle
			(at -14.99997 1.999996 270)
			(size 0.4572 0.4572)
			(layers "F.Cu" "F.Mask" "F.Paste")
			(net "PCIE_RX_N49")
		)
		(pad "AA5" smd circle
			(at -13.999972 1.999996 270)
			(size 0.4572 0.4572)
			(layers "F.Cu" "F.Mask" "F.Paste")
			(net "PCIE_RX_P49")
		)
		(pad "AA6" smd circle
			(at -12.999974 1.999996 270)
			(size 0.4572 0.4572)
			(layers "F.Cu" "F.Mask" "F.Paste")
			(net "GND")
		)
		(pad "AA7" smd circle
			(at -11.999976 1.999996 270)
			(size 0.4572 0.4572)
			(layers "F.Cu" "F.Mask" "F.Paste")
			(net "DUT_AVD_TX")
		)
		(pad "AA8" smd circle
			(at -10.999978 1.999996 270)
			(size 0.4572 0.4572)
			(layers "F.Cu" "F.Mask" "F.Paste")
			(net "GND")
		)
		(pad "AA9" smd circle
			(at -9.99998 1.999996 270)
			(size 0.4572 0.4572)
			(layers "F.Cu" "F.Mask" "F.Paste")
			(net "DUT_AVD_TX")
		)
		(pad "AA10" smd circle
			(at -8.999982 1.999996 270)
			(size 0.4572 0.4572)
			(layers "F.Cu" "F.Mask" "F.Paste")
			(net "GND")
		)
		(pad "AA11" smd circle
			(at -7.999984 1.999996 270)
			(size 0.4572 0.4572)
			(layers "F.Cu" "F.Mask" "F.Paste")
			(net "DUT_AVD_TX")
		)
		(pad "AA12" smd circle
			(at -6.999986 1.999996 270)
			(size 0.4572 0.4572)
			(layers "F.Cu" "F.Mask" "F.Paste")
			(net "GND")
		)
		(pad "AA13" smd circle
			(at -5.999988 1.999996 270)
			(size 0.4572 0.4572)
			(layers "F.Cu" "F.Mask" "F.Paste")
			(net "GND")
		)
		(pad "AA14" smd circle
			(at -4.99999 1.999996 270)
			(size 0.4572 0.4572)
			(layers "F.Cu" "F.Mask" "F.Paste")
			(net "DUT_VDD")
		)
		(pad "AA15" smd circle
			(at -3.999992 1.999996 270)
			(size 0.4572 0.4572)
			(layers "F.Cu" "F.Mask" "F.Paste")
			(net "GND")
		)
		(pad "AA16" smd circle
			(at -2.999994 1.999996 270)
			(size 0.4572 0.4572)
			(layers "F.Cu" "F.Mask" "F.Paste")
			(net "DUT_VDD")
		)
		(pad "AA17" smd circle
			(at -1.999996 1.999996 270)
			(size 0.4572 0.4572)
			(layers "F.Cu" "F.Mask" "F.Paste")
			(net "GND")
		)
		(pad "AA18" smd circle
			(at -0.999998 1.999996 270)
			(size 0.4572 0.4572)
			(layers "F.Cu" "F.Mask" "F.Paste")
			(net "DUT_VDD")
		)
		(pad "AA19" smd circle
			(at 0 1.999996 270)
			(size 0.4572 0.4572)
			(layers "F.Cu" "F.Mask" "F.Paste")
			(net "GND")
		)
		(pad "AA20" smd circle
			(at 0.999998 1.999996 270)
			(size 0.4572 0.4572)
			(layers "F.Cu" "F.Mask" "F.Paste")
			(net "DUT_VDD")
		)
		(pad "AA21" smd circle
			(at 1.999996 1.999996 270)
			(size 0.4572 0.4572)
			(layers "F.Cu" "F.Mask" "F.Paste")
			(net "GND")
		)
		(pad "AA22" smd circle
			(at 2.999994 1.999996 270)
			(size 0.4572 0.4572)
			(layers "F.Cu" "F.Mask" "F.Paste")
			(net "DUT_VDD")
		)
		(pad "AA23" smd circle
			(at 3.999992 1.999996 270)
			(size 0.4572 0.4572)
			(layers "F.Cu" "F.Mask" "F.Paste")
			(net "GND")
		)
		(pad "AA24" smd circle
			(at 4.99999 1.999996 270)
			(size 0.4572 0.4572)
			(layers "F.Cu" "F.Mask" "F.Paste")
			(net "DUT_VDD")
		)
		(pad "AA25" smd circle
			(at 5.999988 1.999996 270)
			(size 0.4572 0.4572)
			(layers "F.Cu" "F.Mask" "F.Paste")
			(net "GND")
		)
		(pad "AA26" smd circle
			(at 6.999986 1.999996 270)
			(size 0.4572 0.4572)
			(layers "F.Cu" "F.Mask" "F.Paste")
			(net "DUT_VDDO")
		)
		(pad "AA27" smd circle
			(at 7.999984 1.999996 270)
			(size 0.4572 0.4572)
			(layers "F.Cu" "F.Mask" "F.Paste")
			(net "BOOTSTRAP_R_10")
		)
		(pad "AA28" smd circle
			(at 8.999982 1.999996 270)
			(size 0.4572 0.4572)
			(layers "F.Cu" "F.Mask" "F.Paste")
			(net "GND")
		)
		(pad "AA29" smd circle
			(at 9.99998 1.999996 270)
			(size 0.4572 0.4572)
			(layers "F.Cu" "F.Mask" "F.Paste")
			(net "PCIE_REFCLK_H2_P")
		)
		(pad "AA30" smd circle
			(at 10.999978 1.999996 270)
			(size 0.4572 0.4572)
			(layers "F.Cu" "F.Mask" "F.Paste")
			(net "PCIE_REFCLK_H2_N")
		)
		(pad "AA31" smd circle
			(at 11.999976 1.999996 270)
			(size 0.4572 0.4572)
			(layers "F.Cu" "F.Mask" "F.Paste")
			(net "DUT_VDDO_REF")
		)
		(pad "AA32" smd circle
			(at 12.999974 1.999996 270)
			(size 0.4572 0.4572)
			(layers "F.Cu" "F.Mask" "F.Paste")
			(net "PCIE_REFCLK_S3_P")
		)
		(pad "AA33" smd circle
			(at 13.999972 1.999996 270)
			(size 0.4572 0.4572)
			(layers "F.Cu" "F.Mask" "F.Paste")
			(net "PCIE_REFCLK_S3_N")
		)
		(pad "AA34" smd circle
			(at 14.99997 1.999996 270)
			(size 0.4572 0.4572)
			(layers "F.Cu" "F.Mask" "F.Paste")
			(net "DUT_VDDO_REF")
		)
		(pad "AA35" smd circle
			(at 15.999968 1.999996 270)
			(size 0.4572 0.4572)
			(layers "F.Cu" "F.Mask" "F.Paste")
			(net "GND")
		)
		(pad "AA36" smd circle
			(at 16.999966 1.999996 270)
			(size 0.4572 0.4572)
			(layers "F.Cu" "F.Mask" "F.Paste")
			(net "PCIE_RX_P95")
		)
		(pad "AA37" smd circle
			(at 17.999964 1.999996 270)
			(size 0.4572 0.4572)
			(layers "F.Cu" "F.Mask" "F.Paste")
			(net "PCIE_RX_N95")
		)
		(pad "AB2" smd circle
			(at -16.999966 2.999994 270)
			(size 0.4572 0.4572)
			(layers "F.Cu" "F.Mask" "F.Paste")
			(net "PCIE_TX_CAP_N50")
		)
		(pad "AB3" smd circle
			(at -15.999968 2.999994 270)
			(size 0.4572 0.4572)
			(layers "F.Cu" "F.Mask" "F.Paste")
			(net "PCIE_TX_CAP_P50")
		)
		(pad "AB4" smd circle
			(at -14.99997 2.999994 270)
			(size 0.4572 0.4572)
			(layers "F.Cu" "F.Mask" "F.Paste")
			(net "GND")
		)
		(pad "AB5" smd circle
			(at -13.999972 2.999994 270)
			(size 0.4572 0.4572)
			(layers "F.Cu" "F.Mask" "F.Paste")
			(net "PCIE_RX_N50")
		)
		(pad "AB6" smd circle
			(at -12.999974 2.999994 270)
			(size 0.4572 0.4572)
			(layers "F.Cu" "F.Mask" "F.Paste")
			(net "PCIE_RX_P50")
		)
		(pad "AB7" smd circle
			(at -11.999976 2.999994 270)
			(size 0.4572 0.4572)
			(layers "F.Cu" "F.Mask" "F.Paste")
			(net "GND")
		)
		(pad "AB8" smd circle
			(at -10.999978 2.999994 270)
			(size 0.4572 0.4572)
			(layers "F.Cu" "F.Mask" "F.Paste")
			(net "DUT_AVD_TX")
		)
		(pad "AB9" smd circle
			(at -9.99998 2.999994 270)
			(size 0.4572 0.4572)
			(layers "F.Cu" "F.Mask" "F.Paste")
			(net "GND")
		)
		(pad "AB10" smd circle
			(at -8.999982 2.999994 270)
			(size 0.4572 0.4572)
			(layers "F.Cu" "F.Mask" "F.Paste")
			(net "DUT_AVD_TX")
		)
		(pad "AB11" smd circle
			(at -7.999984 2.999994 270)
			(size 0.4572 0.4572)
			(layers "F.Cu" "F.Mask" "F.Paste")
			(net "GND")
		)
		(pad "AB12" smd circle
			(at -6.999986 2.999994 270)
			(size 0.4572 0.4572)
			(layers "F.Cu" "F.Mask" "F.Paste")
			(net "GND")
		)
		(pad "AB13" smd circle
			(at -5.999988 2.999994 270)
			(size 0.4572 0.4572)
			(layers "F.Cu" "F.Mask" "F.Paste")
			(net "DUT_VDD")
		)
		(pad "AB14" smd circle
			(at -4.99999 2.999994 270)
			(size 0.4572 0.4572)
			(layers "F.Cu" "F.Mask" "F.Paste")
			(net "GND")
		)
		(pad "AB15" smd circle
			(at -3.999992 2.999994 270)
			(size 0.4572 0.4572)
			(layers "F.Cu" "F.Mask" "F.Paste")
			(net "DUT_VDD")
		)
		(pad "AB16" smd circle
			(at -2.999994 2.999994 270)
			(size 0.4572 0.4572)
			(layers "F.Cu" "F.Mask" "F.Paste")
			(net "GND")
		)
		(pad "AB17" smd circle
			(at -1.999996 2.999994 270)
			(size 0.4572 0.4572)
			(layers "F.Cu" "F.Mask" "F.Paste")
			(net "DUT_VDD")
		)
		(pad "AB18" smd circle
			(at -0.999998 2.999994 270)
			(size 0.4572 0.4572)
			(layers "F.Cu" "F.Mask" "F.Paste")
			(net "GND")
		)
		(pad "AB19" smd circle
			(at 0 2.999994 270)
			(size 0.4572 0.4572)
			(layers "F.Cu" "F.Mask" "F.Paste")
			(net "DUT_VDD")
		)
		(pad "AB20" smd circle
			(at 0.999998 2.999994 270)
			(size 0.4572 0.4572)
			(layers "F.Cu" "F.Mask" "F.Paste")
			(net "GND")
		)
		(pad "AB21" smd circle
			(at 1.999996 2.999994 270)
			(size 0.4572 0.4572)
			(layers "F.Cu" "F.Mask" "F.Paste")
			(net "DUT_VDD")
		)
		(pad "AB22" smd circle
			(at 2.999994 2.999994 270)
			(size 0.4572 0.4572)
			(layers "F.Cu" "F.Mask" "F.Paste")
			(net "GND")
		)
		(pad "AB23" smd circle
			(at 3.999992 2.999994 270)
			(size 0.4572 0.4572)
			(layers "F.Cu" "F.Mask" "F.Paste")
			(net "DUT_VDD")
		)
		(pad "AB24" smd circle
			(at 4.99999 2.999994 270)
			(size 0.4572 0.4572)
			(layers "F.Cu" "F.Mask" "F.Paste")
			(net "GND")
		)
		(pad "AB25" smd circle
			(at 5.999988 2.999994 270)
			(size 0.4572 0.4572)
			(layers "F.Cu" "F.Mask" "F.Paste")
			(net "DUT_VDD")
		)
		(pad "AB26" smd circle
			(at 6.999986 2.999994 270)
			(size 0.4572 0.4572)
			(layers "F.Cu" "F.Mask" "F.Paste")
			(net "GND")
		)
		(pad "AB27" smd circle
			(at 7.999984 2.999994 270)
			(size 0.4572 0.4572)
			(layers "F.Cu" "F.Mask" "F.Paste")
			(net "LBI_ADDR_1_R")
		)
		(pad "AB28" smd circle
			(at 8.999982 2.999994 270)
			(size 0.4572 0.4572)
			(layers "F.Cu" "F.Mask" "F.Paste")
			(net "LBI_ADDR_0_R")
		)
		(pad "AB29" smd circle
			(at 9.99998 2.999994 270)
			(size 0.4572 0.4572)
			(layers "F.Cu" "F.Mask" "F.Paste")
			(net "PCIE_REFCLK_H1_P")
		)
		(pad "AB30" smd circle
			(at 10.999978 2.999994 270)
			(size 0.4572 0.4572)
			(layers "F.Cu" "F.Mask" "F.Paste")
			(net "PCIE_REFCLK_H1_N")
		)
		(pad "AB31" smd circle
			(at 11.999976 2.999994 270)
			(size 0.4572 0.4572)
			(layers "F.Cu" "F.Mask" "F.Paste")
			(net "GND")
		)
		(pad "AB32" smd circle
			(at 12.999974 2.999994 270)
			(size 0.4572 0.4572)
			(layers "F.Cu" "F.Mask" "F.Paste")
			(net "PCIE_REFCLK_S2_P")
		)
		(pad "AB33" smd circle
			(at 13.999972 2.999994 270)
			(size 0.4572 0.4572)
			(layers "F.Cu" "F.Mask" "F.Paste")
			(net "PCIE_REFCLK_S2_N")
		)
		(pad "AB34" smd circle
			(at 14.99997 2.999994 270)
			(size 0.4572 0.4572)
			(layers "F.Cu" "F.Mask" "F.Paste")
			(net "GND")
		)
		(pad "AB35" smd circle
			(at 15.999968 2.999994 270)
			(size 0.4572 0.4572)
			(layers "F.Cu" "F.Mask" "F.Paste")
			(net "PCIE_RX_P94")
		)
		(pad "AB36" smd circle
			(at 16.999966 2.999994 270)
			(size 0.4572 0.4572)
			(layers "F.Cu" "F.Mask" "F.Paste")
			(net "PCIE_RX_N94")
		)
		(pad "AC1" smd circle
			(at -17.999964 3.999992 270)
			(size 0.4572 0.4572)
			(layers "F.Cu" "F.Mask" "F.Paste")
			(net "PCIE_TX_CAP_N51")
		)
		(pad "AC2" smd circle
			(at -16.999966 3.999992 270)
			(size 0.4572 0.4572)
			(layers "F.Cu" "F.Mask" "F.Paste")
			(net "PCIE_TX_CAP_P51")
		)
		(pad "AC3" smd circle
			(at -15.999968 3.999992 270)
			(size 0.4572 0.4572)
			(layers "F.Cu" "F.Mask" "F.Paste")
			(net "GND")
		)
		(pad "AC4" smd circle
			(at -14.99997 3.999992 270)
			(size 0.4572 0.4572)
			(layers "F.Cu" "F.Mask" "F.Paste")
			(net "PCIE_RX_N51")
		)
		(pad "AC5" smd circle
			(at -13.999972 3.999992 270)
			(size 0.4572 0.4572)
			(layers "F.Cu" "F.Mask" "F.Paste")
			(net "PCIE_RX_P51")
		)
		(pad "AC6" smd circle
			(at -12.999974 3.999992 270)
			(size 0.4572 0.4572)
			(layers "F.Cu" "F.Mask" "F.Paste")
			(net "GND")
		)
		(pad "AC7" smd circle
			(at -11.999976 3.999992 270)
			(size 0.4572 0.4572)
			(layers "F.Cu" "F.Mask" "F.Paste")
			(net "DUT_AVD_TX")
		)
		(pad "AC8" smd circle
			(at -10.999978 3.999992 270)
			(size 0.4572 0.4572)
			(layers "F.Cu" "F.Mask" "F.Paste")
			(net "GND")
		)
		(pad "AC9" smd circle
			(at -9.99998 3.999992 270)
			(size 0.4572 0.4572)
			(layers "F.Cu" "F.Mask" "F.Paste")
			(net "DUT_AVD_TX")
		)
		(pad "AC10" smd circle
			(at -8.999982 3.999992 270)
			(size 0.4572 0.4572)
			(layers "F.Cu" "F.Mask" "F.Paste")
			(net "GND")
		)
		(pad "AC11" smd circle
			(at -7.999984 3.999992 270)
			(size 0.4572 0.4572)
			(layers "F.Cu" "F.Mask" "F.Paste")
			(net "DUT_AVD_TX")
		)
		(pad "AC12" smd circle
			(at -6.999986 3.999992 270)
			(size 0.4572 0.4572)
			(layers "F.Cu" "F.Mask" "F.Paste")
			(net "GND")
		)
		(pad "AC13" smd circle
			(at -5.999988 3.999992 270)
			(size 0.4572 0.4572)
			(layers "F.Cu" "F.Mask" "F.Paste")
			(net "GND")
		)
		(pad "AC14" smd circle
			(at -4.99999 3.999992 270)
			(size 0.4572 0.4572)
			(layers "F.Cu" "F.Mask" "F.Paste")
			(net "DUT_VDD")
		)
		(pad "AC15" smd circle
			(at -3.999992 3.999992 270)
			(size 0.4572 0.4572)
			(layers "F.Cu" "F.Mask" "F.Paste")
			(net "GND")
		)
		(pad "AC16" smd circle
			(at -2.999994 3.999992 270)
			(size 0.4572 0.4572)
			(layers "F.Cu" "F.Mask" "F.Paste")
			(net "DUT_VDD")
		)
		(pad "AC17" smd circle
			(at -1.999996 3.999992 270)
			(size 0.4572 0.4572)
			(layers "F.Cu" "F.Mask" "F.Paste")
			(net "GND")
		)
		(pad "AC18" smd circle
			(at -0.999998 3.999992 270)
			(size 0.4572 0.4572)
			(layers "F.Cu" "F.Mask" "F.Paste")
			(net "DUT_VDD")
		)
		(pad "AC19" smd circle
			(at 0 3.999992 270)
			(size 0.4572 0.4572)
			(layers "F.Cu" "F.Mask" "F.Paste")
			(net "GND")
		)
		(pad "AC20" smd circle
			(at 0.999998 3.999992 270)
			(size 0.4572 0.4572)
			(layers "F.Cu" "F.Mask" "F.Paste")
			(net "DUT_VDD")
		)
		(pad "AC21" smd circle
			(at 1.999996 3.999992 270)
			(size 0.4572 0.4572)
			(layers "F.Cu" "F.Mask" "F.Paste")
			(net "GND")
		)
		(pad "AC22" smd circle
			(at 2.999994 3.999992 270)
			(size 0.4572 0.4572)
			(layers "F.Cu" "F.Mask" "F.Paste")
			(net "DUT_VDD")
		)
	)
)
